(kicad_pcb
	(version 20260206)
	(generator "pcbnew")
	(generator_version "10.0")
	(general
		(thickness 1.6)
		(legacy_teardrops no)
	)
	(paper "A4")
	(title_block
		(title "baseboard — 13948-1b.1110WZS1818.brd")
		(comment 1 "Honey Badger (Wiwynn) / footprint 1028 of 2523 (U40), pads 1-111 of 408")
	)
	(layers
		(0 "F.Cu" signal "TOP")
		(4 "In1.Cu" signal "L2GND")
		(6 "In2.Cu" signal "L3")
		(8 "In3.Cu" signal "L4VCC")
		(10 "In4.Cu" signal "L5VCC")
		(12 "In5.Cu" signal "L6")
		(14 "In6.Cu" signal "L7GND")
		(2 "B.Cu" signal "BOTTOM")
		(9 "F.Adhes" user "F.Adhesive")
		(11 "B.Adhes" user "B.Adhesive")
		(13 "F.Paste" user "Package Geometry/Pastemask Top")
		(15 "B.Paste" user "Package Geometry/Pastemask Bottom")
		(5 "F.SilkS" user "Ref Des/Silkscreen Top")
		(7 "B.SilkS" user "Ref Des/Silkscreen Bottom")
		(1 "F.Mask" user "Board Geometry/Soldermask Top")
		(3 "B.Mask" user "Board Geometry/Soldermask Bottom")
		(17 "Dwgs.User" user "User.Drawings")
		(19 "Cmts.User" user "User.Comments")
		(21 "Eco1.User" user "User.Eco1")
		(23 "Eco2.User" user "User.Eco2")
		(25 "Edge.Cuts" user "Board Geometry/Outline")
		(27 "Margin" user)
		(31 "F.CrtYd" user "Package Geometry/Place Bound Top")
		(29 "B.CrtYd" user "Package Geometry/Place Bound Bottom")
		(35 "F.Fab" user "Ref Des/Assembly Top")
		(33 "B.Fab" user "Ref Des/Assembly Bottom")
	)
	(footprint ""
		(layer "F.Cu")
		(at 293.234872 -175.840136 180)
		(property "Reference" "U40"
			(at 0 0 180)
			(layer "F.SilkS")
			(hide yes)
			(effects
				(font
					(size 1.27 1.27)
				)
			)
		)
		(property "Value" "AST1250A1-GP"
			(at -17.7292 -6.184392 180)
			(unlocked yes)
			(layer "F.Fab")
			(hide yes)
			(effects
				(font
					(size 1.016 1.016)
					(thickness 0.1524)
				)
			)
		)
		(property "Device Type" "BGA408D19H52"
			(at -17.7292 -7.708392 180)
			(unlocked yes)
			(layer "F.Fab")
			(hide yes)
			(effects
				(font
					(size 1.016 1.016)
					(thickness 0.1524)
				)
			)
		)
		(duplicate_pad_numbers_are_jumpers no)
		(pad "A1" smd circle
			(at -8.400034 -8.400034 180)
			(size 0.4064 0.4064)
			(layers "F.Cu" "F.Mask" "F.Paste")
			(net "PU_BMC0_SDA13")
		)
		(pad "A2" smd circle
			(at -7.599934 -8.400034 180)
			(size 0.4064 0.4064)
			(layers "F.Cu" "F.Mask" "F.Paste")
			(net "PU_BMC0_SCL11")
		)
		(pad "A3" smd circle
			(at -6.800088 -8.400034 180)
			(size 0.4064 0.4064)
			(layers "F.Cu" "F.Mask" "F.Paste")
			(net "TP_BMC_GPIOA6")
		)
		(pad "A4" smd circle
			(at -5.999988 -8.400034 180)
			(size 0.3556 0.3556)
			(layers "F.Cu" "F.Mask" "F.Paste")
			(net "DP_BMC_CPU_RST_N_R")
		)
		(pad "A5" smd circle
			(at -5.199888 -8.400034 180)
			(size 0.3556 0.3556)
			(layers "F.Cu" "F.Mask" "F.Paste")
			(net "RMII_BMC_MDIO")
		)
		(pad "A6" smd circle
			(at -4.400042 -8.400034 180)
			(size 0.3556 0.3556)
			(layers "F.Cu" "F.Mask" "F.Paste")
			(net "TP_GPIOH6")
		)
		(pad "A7" smd circle
			(at -3.599942 -8.400034 180)
			(size 0.3556 0.3556)
			(layers "F.Cu" "F.Mask" "F.Paste")
			(net "TP_GPIOH3")
		)
		(pad "A8" smd circle
			(at -2.800096 -8.400034 180)
			(size 0.3556 0.3556)
			(layers "F.Cu" "F.Mask" "F.Paste")
			(net "Net_1333")
		)
		(pad "A9" smd circle
			(at -1.999996 -8.400034 180)
			(size 0.3556 0.3556)
			(layers "F.Cu" "F.Mask" "F.Paste")
			(net "NCSI_10G_RXD0")
		)
		(pad "A10" smd circle
			(at -1.199896 -8.400034 180)
			(size 0.3556 0.3556)
			(layers "F.Cu" "F.Mask" "F.Paste")
			(net "NCSI_10G_TXD0")
		)
		(pad "A11" smd circle
			(at -0.40005 -8.400034 180)
			(size 0.3556 0.3556)
			(layers "F.Cu" "F.Mask" "F.Paste")
			(net "RMII0_BMC_C_CRS_DV")
		)
		(pad "A12" smd circle
			(at 0.40005 -8.400034 180)
			(size 0.3556 0.3556)
			(layers "F.Cu" "F.Mask" "F.Paste")
			(net "RMII0_BMC_C_TX_EN")
		)
		(pad "A13" smd circle
			(at 1.199896 -8.400034 180)
			(size 0.3556 0.3556)
			(layers "F.Cu" "F.Mask" "F.Paste")
			(net "GND")
		)
		(pad "A14" smd circle
			(at 1.999996 -8.400034 180)
			(size 0.3556 0.3556)
			(layers "F.Cu" "F.Mask" "F.Paste")
			(net "HIGH_HEX_0")
		)
		(pad "A15" smd circle
			(at 2.800096 -8.400034 180)
			(size 0.3556 0.3556)
			(layers "F.Cu" "F.Mask" "F.Paste")
			(net "TP_BMC_GPIOE3")
		)
		(pad "A16" smd circle
			(at 3.599942 -8.400034 180)
			(size 0.3556 0.3556)
			(layers "F.Cu" "F.Mask" "F.Paste")
			(net "BMC_LSI_BOARD")
		)
		(pad "A17" smd circle
			(at 4.400042 -8.400034 180)
			(size 0.3556 0.3556)
			(layers "F.Cu" "F.Mask" "F.Paste")
			(net "BMC_PWRBTN_N_R")
		)
		(pad "A18" smd circle
			(at 5.199888 -8.400034 180)
			(size 0.3556 0.3556)
			(layers "F.Cu" "F.Mask" "F.Paste")
			(net "SYS_RSTBTN_N_R")
		)
		(pad "A19" smd circle
			(at 5.999988 -8.400034 180)
			(size 0.3556 0.3556)
			(layers "F.Cu" "F.Mask" "F.Paste")
			(net "TP_BMC_GPIOF5")
		)
		(pad "A20" smd circle
			(at 6.800088 -8.400034 180)
			(size 0.4064 0.4064)
			(layers "F.Cu" "F.Mask" "F.Paste")
			(net "TP_BMC_GPIOF2")
		)
		(pad "A21" smd circle
			(at 7.599934 -8.400034 180)
			(size 0.4064 0.4064)
			(layers "F.Cu" "F.Mask" "F.Paste")
			(net "TP_LPC_CPU_FRAME_N")
		)
		(pad "A22" smd circle
			(at 8.400034 -8.400034 180)
			(size 0.4064 0.4064)
			(layers "F.Cu" "F.Mask" "F.Paste")
			(net "TP_BMC0_LPC_LAD1")
		)
		(pad "AA1" smd circle
			(at -8.400034 7.599934 180)
			(size 0.4064 0.4064)
			(layers "F.Cu" "F.Mask" "F.Paste")
			(net "TP_BMC_GPIOM6")
		)
		(pad "AA2" smd circle
			(at -7.599934 7.599934 180)
			(size 0.4064 0.4064)
			(layers "F.Cu" "F.Mask" "F.Paste")
			(net "BMC0_LED_DR_R_LED1")
		)
		(pad "AA3" smd circle
			(at -6.800088 7.599934 180)
			(size 0.4064 0.4064)
			(layers "F.Cu" "F.Mask" "F.Paste")
			(net "BMC_FW_DET_BOARD_VER_1")
		)
		(pad "AA4" smd circle
			(at -5.999988 7.599934 180)
			(size 0.3556 0.3556)
			(layers "F.Cu" "F.Mask" "F.Paste")
			(net "HB0_R_IN2")
		)
		(pad "AA5" smd circle
			(at -5.199888 7.599934 180)
			(size 0.3556 0.3556)
			(layers "F.Cu" "F.Mask" "F.Paste")
			(net "CONN_10G_PRSNT2_N")
		)
		(pad "AA6" smd circle
			(at -4.400042 7.599934 180)
			(size 0.3556 0.3556)
			(layers "F.Cu" "F.Mask" "F.Paste")
			(net "BMC0_TACH11")
		)
		(pad "AA7" smd circle
			(at -3.599942 7.599934 180)
			(size 0.3556 0.3556)
			(layers "F.Cu" "F.Mask" "F.Paste")
			(net "BMC0_TACH14")
		)
		(pad "AA8" smd circle
			(at -2.800096 7.599934 180)
			(size 0.3556 0.3556)
			(layers "F.Cu" "F.Mask" "F.Paste")
			(net "MEMDQS_P1")
		)
		(pad "AA9" smd circle
			(at -1.999996 7.599934 180)
			(size 0.3556 0.3556)
			(layers "F.Cu" "F.Mask" "F.Paste")
			(net "MEMDQ_10")
		)
		(pad "AA10" smd circle
			(at -1.199896 7.599934 180)
			(size 0.3556 0.3556)
			(layers "F.Cu" "F.Mask" "F.Paste")
			(net "MEMDQS_N0")
		)
		(pad "AA11" smd circle
			(at -0.40005 7.599934 180)
			(size 0.3556 0.3556)
			(layers "F.Cu" "F.Mask" "F.Paste")
			(net "MEMDQ_3")
		)
		(pad "AA12" smd circle
			(at 0.40005 7.599934 180)
			(size 0.3556 0.3556)
			(layers "F.Cu" "F.Mask" "F.Paste")
			(net "MEMCK_N")
		)
		(pad "AA13" smd circle
			(at 1.199896 7.599934 180)
			(size 0.3556 0.3556)
			(layers "F.Cu" "F.Mask" "F.Paste")
			(net "MEMCSN")
		)
		(pad "AA14" smd circle
			(at 1.999996 7.599934 180)
			(size 0.3556 0.3556)
			(layers "F.Cu" "F.Mask" "F.Paste")
			(net "MEMBA_1")
		)
		(pad "AA15" smd circle
			(at 2.800096 7.599934 180)
			(size 0.3556 0.3556)
			(layers "F.Cu" "F.Mask" "F.Paste")
			(net "MEMA_6")
		)
		(pad "AA16" smd circle
			(at 3.599942 7.599934 180)
			(size 0.3556 0.3556)
			(layers "F.Cu" "F.Mask" "F.Paste")
			(net "MEMA_11")
		)
		(pad "AA17" smd circle
			(at 4.400042 7.599934 180)
			(size 0.3556 0.3556)
			(layers "F.Cu" "F.Mask" "F.Paste")
			(net "MEMA_9")
		)
		(pad "AA18" smd circle
			(at 5.199888 7.599934 180)
			(size 0.3556 0.3556)
			(layers "F.Cu" "F.Mask" "F.Paste")
			(net "GND")
		)
		(pad "AA19" smd circle
			(at 5.999988 7.599934 180)
			(size 0.3556 0.3556)
			(layers "F.Cu" "F.Mask" "F.Paste")
			(net "GND")
		)
		(pad "AA20" smd circle
			(at 6.800088 7.599934 180)
			(size 0.4064 0.4064)
			(layers "F.Cu" "F.Mask" "F.Paste")
			(net "PD_USB2VRES")
		)
		(pad "AA21" smd circle
			(at 7.599934 7.599934 180)
			(size 0.4064 0.4064)
			(layers "F.Cu" "F.Mask" "F.Paste")
			(net "PECI0_R")
		)
		(pad "AA22" smd circle
			(at 8.400034 7.599934 180)
			(size 0.4064 0.4064)
			(layers "F.Cu" "F.Mask" "F.Paste")
			(net "DP_RST_N_R")
		)
		(pad "AB1" smd circle
			(at -8.400034 8.400034 180)
			(size 0.4064 0.4064)
			(layers "F.Cu" "F.Mask" "F.Paste")
			(net "BMC0_LED_DR_R_LED0")
		)
		(pad "AB2" smd circle
			(at -7.599934 8.400034 180)
			(size 0.4064 0.4064)
			(layers "F.Cu" "F.Mask" "F.Paste")
			(net "BMC_FW_DET_BOARD_VER_2")
		)
		(pad "AB3" smd circle
			(at -6.800088 8.400034 180)
			(size 0.4064 0.4064)
			(layers "F.Cu" "F.Mask" "F.Paste")
			(net "HB_OUT_BMC")
		)
		(pad "AB4" smd circle
			(at -5.999988 8.400034 180)
			(size 0.3556 0.3556)
			(layers "F.Cu" "F.Mask" "F.Paste")
			(net "BMC_EN_CPU_RESET_CONTROL")
		)
		(pad "AB5" smd circle
			(at -5.199888 8.400034 180)
			(size 0.3556 0.3556)
			(layers "F.Cu" "F.Mask" "F.Paste")
			(net "BMC0_TACH9")
		)
		(pad "AB6" smd circle
			(at -4.400042 8.400034 180)
			(size 0.3556 0.3556)
			(layers "F.Cu" "F.Mask" "F.Paste")
			(net "BMC0_TACH12")
		)
		(pad "AB7" smd circle
			(at -3.599942 8.400034 180)
			(size 0.3556 0.3556)
			(layers "F.Cu" "F.Mask" "F.Paste")
			(net "BMC0_TACH15")
		)
		(pad "AB8" smd circle
			(at -2.800096 8.400034 180)
			(size 0.3556 0.3556)
			(layers "F.Cu" "F.Mask" "F.Paste")
			(net "MEMDQS_N1")
		)
		(pad "AB9" smd circle
			(at -1.999996 8.400034 180)
			(size 0.3556 0.3556)
			(layers "F.Cu" "F.Mask" "F.Paste")
			(net "MEMDQ_9")
		)
		(pad "AB10" smd circle
			(at -1.199896 8.400034 180)
			(size 0.3556 0.3556)
			(layers "F.Cu" "F.Mask" "F.Paste")
			(net "MEMDQS_P0")
		)
		(pad "AB11" smd circle
			(at -0.40005 8.400034 180)
			(size 0.3556 0.3556)
			(layers "F.Cu" "F.Mask" "F.Paste")
			(net "MEMDQ_2")
		)
		(pad "AB12" smd circle
			(at 0.40005 8.400034 180)
			(size 0.3556 0.3556)
			(layers "F.Cu" "F.Mask" "F.Paste")
			(net "MEMCK_P")
		)
		(pad "AB13" smd circle
			(at 1.199896 8.400034 180)
			(size 0.3556 0.3556)
			(layers "F.Cu" "F.Mask" "F.Paste")
			(net "MEMCASN")
		)
		(pad "AB14" smd circle
			(at 1.999996 8.400034 180)
			(size 0.3556 0.3556)
			(layers "F.Cu" "F.Mask" "F.Paste")
			(net "MEMA_0")
		)
		(pad "AB15" smd circle
			(at 2.800096 8.400034 180)
			(size 0.3556 0.3556)
			(layers "F.Cu" "F.Mask" "F.Paste")
			(net "MEMA_4")
		)
		(pad "AB16" smd circle
			(at 3.599942 8.400034 180)
			(size 0.3556 0.3556)
			(layers "F.Cu" "F.Mask" "F.Paste")
			(net "MEMA_8")
		)
		(pad "AB17" smd circle
			(at 4.400042 8.400034 180)
			(size 0.3556 0.3556)
			(layers "F.Cu" "F.Mask" "F.Paste")
			(net "MEMA_14")
		)
		(pad "AB18" smd circle
			(at 5.199888 8.400034 180)
			(size 0.3556 0.3556)
			(layers "F.Cu" "F.Mask" "F.Paste")
			(net "MEMA_7")
		)
		(pad "AB19" smd circle
			(at 5.999988 8.400034 180)
			(size 0.3556 0.3556)
			(layers "F.Cu" "F.Mask" "F.Paste")
			(net "MPLLAV33")
		)
		(pad "AB20" smd circle
			(at 6.800088 8.400034 180)
			(size 0.4064 0.4064)
			(layers "F.Cu" "F.Mask" "F.Paste")
			(net "BMC_USB2_HDN")
		)
		(pad "AB21" smd circle
			(at 7.599934 8.400034 180)
			(size 0.4064 0.4064)
			(layers "F.Cu" "F.Mask" "F.Paste")
			(net "BMC_USB2_HDP")
		)
		(pad "AB22" smd circle
			(at 8.400034 8.400034 180)
			(size 0.4064 0.4064)
			(layers "F.Cu" "F.Mask" "F.Paste")
			(net "OSC0_AS_CLKIN")
		)
		(pad "B1" smd circle
			(at -8.400034 -7.599934 180)
			(size 0.4064 0.4064)
			(layers "F.Cu" "F.Mask" "F.Paste")
			(net "BMC0_SMB4_CLK")
		)
		(pad "B2" smd circle
			(at -7.599934 -7.599934 180)
			(size 0.4064 0.4064)
			(layers "F.Cu" "F.Mask" "F.Paste")
			(net "PU_BMC0_SCL13")
		)
		(pad "B3" smd circle
			(at -6.800088 -7.599934 180)
			(size 0.4064 0.4064)
			(layers "F.Cu" "F.Mask" "F.Paste")
			(net "BMC0_SMB10_DAT")
		)
		(pad "B4" smd circle
			(at -5.999988 -7.599934 180)
			(size 0.3556 0.3556)
			(layers "F.Cu" "F.Mask" "F.Paste")
			(net "BMC0_SMB9_DAT")
		)
		(pad "B5" smd circle
			(at -5.199888 -7.599934 180)
			(size 0.3556 0.3556)
			(layers "F.Cu" "F.Mask" "F.Paste")
			(net "BMC_JTAG_L_EN_R")
		)
		(pad "B6" smd circle
			(at -4.400042 -7.599934 180)
			(size 0.3556 0.3556)
			(layers "F.Cu" "F.Mask" "F.Paste")
			(net "TP_GPIOH5")
		)
		(pad "B7" smd circle
			(at -3.599942 -7.599934 180)
			(size 0.3556 0.3556)
			(layers "F.Cu" "F.Mask" "F.Paste")
			(net "TP_GPIOH2")
		)
		(pad "B8" smd circle
			(at -2.800096 -7.599934 180)
			(size 0.3556 0.3556)
			(layers "F.Cu" "F.Mask" "F.Paste")
			(net "BMC_MAC2_RGMIICK")
		)
		(pad "B9" smd circle
			(at -1.999996 -7.599934 180)
			(size 0.3556 0.3556)
			(layers "F.Cu" "F.Mask" "F.Paste")
			(net "TP_BMC_GPIOV3")
		)
		(pad "B10" smd circle
			(at -1.199896 -7.599934 180)
			(size 0.3556 0.3556)
			(layers "F.Cu" "F.Mask" "F.Paste")
			(net "NCSI_10G_TXD1")
		)
		(pad "B11" smd circle
			(at -0.40005 -7.599934 180)
			(size 0.3556 0.3556)
			(layers "F.Cu" "F.Mask" "F.Paste")
			(net "RMII0_PHY_BMC_C_RXD1")
		)
		(pad "B12" smd circle
			(at 0.40005 -7.599934 180)
			(size 0.3556 0.3556)
			(layers "F.Cu" "F.Mask" "F.Paste")
			(net "GND")
		)
		(pad "B13" smd circle
			(at 1.199896 -7.599934 180)
			(size 0.3556 0.3556)
			(layers "F.Cu" "F.Mask" "F.Paste")
			(net "HDD_PRE_INT_R")
		)
		(pad "B14" smd circle
			(at 1.999996 -7.599934 180)
			(size 0.3556 0.3556)
			(layers "F.Cu" "F.Mask" "F.Paste")
			(net "BMC_RXD1")
		)
		(pad "B15" smd circle
			(at 2.800096 -7.599934 180)
			(size 0.3556 0.3556)
			(layers "F.Cu" "F.Mask" "F.Paste")
			(net "TP_BMC_GPIOE2")
		)
		(pad "B16" smd circle
			(at 3.599942 -7.599934 180)
			(size 0.3556 0.3556)
			(layers "F.Cu" "F.Mask" "F.Paste")
			(net "FM_BMC_READY_N_R")
		)
		(pad "B17" smd circle
			(at 4.400042 -7.599934 180)
			(size 0.3556 0.3556)
			(layers "F.Cu" "F.Mask" "F.Paste")
			(net "SYS_PWRBTN_N_R")
		)
		(pad "B18" smd circle
			(at 5.199888 -7.599934 180)
			(size 0.3556 0.3556)
			(layers "F.Cu" "F.Mask" "F.Paste")
			(net "TP_BMC_GPIOF4")
		)
		(pad "B19" smd circle
			(at 5.999988 -7.599934 180)
			(size 0.3556 0.3556)
			(layers "F.Cu" "F.Mask" "F.Paste")
			(net "TP_BMC_GPIOF1")
		)
		(pad "B20" smd circle
			(at 6.800088 -7.599934 180)
			(size 0.4064 0.4064)
			(layers "F.Cu" "F.Mask" "F.Paste")
			(net "TP_LPC_CPU_CLKOUT0")
		)
		(pad "B21" smd circle
			(at 7.599934 -7.599934 180)
			(size 0.4064 0.4064)
			(layers "F.Cu" "F.Mask" "F.Paste")
			(net "TP_BMC0_LPC_LAD0")
		)
		(pad "B22" smd circle
			(at 8.400034 -7.599934 180)
			(size 0.4064 0.4064)
			(layers "F.Cu" "F.Mask" "F.Paste")
			(net "BMC_EN_P3V3_R")
		)
		(pad "C1" smd circle
			(at -8.400034 -6.800088 180)
			(size 0.4064 0.4064)
			(layers "F.Cu" "F.Mask" "F.Paste")
			(net "BMC0_SMB6_CLK")
		)
		(pad "C2" smd circle
			(at -7.599934 -6.800088 180)
			(size 0.4064 0.4064)
			(layers "F.Cu" "F.Mask" "F.Paste")
			(net "BMC0_SMB3_DAT")
		)
		(pad "C3" smd circle
			(at -6.800088 -6.800088 180)
			(size 0.4064 0.4064)
			(layers "F.Cu" "F.Mask" "F.Paste")
			(net "PU_BMC0_SDA12")
		)
		(pad "C4" smd circle
			(at -5.999988 -6.800088 180)
			(size 0.3556 0.3556)
			(layers "F.Cu" "F.Mask" "F.Paste")
			(net "BMC0_SMB10_CLK")
		)
		(pad "C5" smd circle
			(at -5.199888 -6.800088 180)
			(size 0.3556 0.3556)
			(layers "F.Cu" "F.Mask" "F.Paste")
			(net "BMC0_SMB9_CLK")
		)
		(pad "C6" smd circle
			(at -4.400042 -6.800088 180)
			(size 0.3556 0.3556)
			(layers "F.Cu" "F.Mask" "F.Paste")
			(net "RMII_BMC_MDC")
		)
		(pad "C7" smd circle
			(at -3.599942 -6.800088 180)
			(size 0.3556 0.3556)
			(layers "F.Cu" "F.Mask" "F.Paste")
			(net "BMC_ID_LED")
		)
		(pad "C8" smd circle
			(at -2.800096 -6.800088 180)
			(size 0.3556 0.3556)
			(layers "F.Cu" "F.Mask" "F.Paste")
			(net "NCSI_10G_RX_ER")
		)
		(pad "C9" smd circle
			(at -1.999996 -6.800088 180)
			(size 0.3556 0.3556)
			(layers "F.Cu" "F.Mask" "F.Paste")
			(net "CLK_50M_BMC_NCSI_R")
		)
		(pad "C10" smd circle
			(at -1.199896 -6.800088 180)
			(size 0.3556 0.3556)
			(layers "F.Cu" "F.Mask" "F.Paste")
			(net "TP_BMC_GPIOU2")
		)
		(pad "C11" smd circle
			(at -0.40005 -6.800088 180)
			(size 0.3556 0.3556)
			(layers "F.Cu" "F.Mask" "F.Paste")
			(net "RMII0_PHY_BMC_C_RXD0")
		)
		(pad "C12" smd circle
			(at 0.40005 -6.800088 180)
			(size 0.3556 0.3556)
			(layers "F.Cu" "F.Mask" "F.Paste")
			(net "RMII0_BMC_C_PHY_TXD0")
		)
		(pad "C13" smd circle
			(at 1.199896 -6.800088 180)
			(size 0.3556 0.3556)
			(layers "F.Cu" "F.Mask" "F.Paste")
			(net "HIGH_HEX_3")
		)
		(pad "C14" smd circle
			(at 1.999996 -6.800088 180)
			(size 0.3556 0.3556)
			(layers "F.Cu" "F.Mask" "F.Paste")
			(net "BMC_TXD1")
		)
		(pad "C15" smd circle
			(at 2.800096 -6.800088 180)
			(size 0.3556 0.3556)
			(layers "F.Cu" "F.Mask" "F.Paste")
			(net "TP_BMC_GPIOE1")
		)
		(pad "C16" smd circle
			(at 3.599942 -6.800088 180)
			(size 0.3556 0.3556)
			(layers "F.Cu" "F.Mask" "F.Paste")
			(net "BMC0_PMU_PLTRST_N_BMC")
		)
		(pad "C17" smd circle
			(at 4.400042 -6.800088 180)
			(size 0.3556 0.3556)
			(layers "F.Cu" "F.Mask" "F.Paste")
			(net "TP_BMC_GPIOF7")
		)
		(pad "C18" smd circle
			(at 5.199888 -6.800088 180)
			(size 0.3556 0.3556)
			(layers "F.Cu" "F.Mask" "F.Paste")
			(net "BMC_EN_0V955_R")
		)
		(pad "C19" smd circle
			(at 5.999988 -6.800088 180)
			(size 0.3556 0.3556)
			(layers "F.Cu" "F.Mask" "F.Paste")
			(net "TP_BMC0_LPC_LAD3")
		)
		(pad "C20" smd circle
			(at 6.800088 -6.800088 180)
			(size 0.4064 0.4064)
			(layers "F.Cu" "F.Mask" "F.Paste")
			(net "PWGD_P0V9_E_PG_R")
		)
		(pad "C21" smd circle
			(at 7.599934 -6.800088 180)
			(size 0.4064 0.4064)
			(layers "F.Cu" "F.Mask" "F.Paste")
			(net "PRSNT_CONTROL_BMC")
		)
		(pad "C22" smd circle
			(at 8.400034 -6.800088 180)
			(size 0.4064 0.4064)
			(layers "F.Cu" "F.Mask" "F.Paste")
			(net "TP_BMC_GPIOI0")
		)
		(pad "D1" smd circle
			(at -8.400034 -5.999988 180)
			(size 0.3556 0.3556)
			(layers "F.Cu" "F.Mask" "F.Paste")
			(net "BMC0_SMB7_DAT")
		)
	)
)
